( ConstraintFile "p12v_stby"
	( constraintHeader
		( objectKey
			( logical )
		)
		( version
			( 16.5 )
		)
		( revisionNumber
			( logicalViewRevNum 2 )
			( physicalViewRevNum 0 )
			( otherViewRevNum 0 )
		)
		( contents
			( dictionaryExtensions )
			( worksheetCustomizations )
			( electricalConstraints )
			( netClasses )
			( properties )
		)
		( precision
			( units mil )
			( numberOfDecimalPlaces 2 )
		)
	)
	( DictionaryExtensions
		( Attribute
			( Name "MATERIAL" )
			( Description " " )
			( Value
				( DataType ( dString ) )
				( Status  sProperty  sPackage )
			)
			( Objects
				( ValidObjects  oGate  oGateDefn  oBlock  oPart  oDesign  oSystem  oPartDefn )
				( NoInherit
					( oGate oPin )
				)
			)
			( Analysis
			)
		)
		( Attribute
			( Name "TOLERANCE" )
			( Description " " )
			( Value
				( DataType ( dString ) )
				( Status  sProperty  sPackage )
			)
			( Objects
				( ValidObjects  oGate  oGateDefn  oBlock  oPart  oDesign  oSystem  oPartDefn )
				( NoInherit
					( oGate oPin )
				)
			)
			( Analysis
			)
		)
		( Attribute
			( Name "WATTAGE" )
			( Description " " )
			( Value
				( DataType ( dString ) )
				( Status  sProperty  sPackage )
			)
			( Objects
				( ValidObjects  oGate  oGateDefn  oBlock  oPart  oDesign  oSystem  oPartDefn )
				( NoInherit
					( oGate oPin )
				)
			)
			( Analysis
			)
		)
		( Attribute
			( Name "CDS_LMAN_SYM_OUTLINE" )
			( Description " " )
			( Value
				( DataType ( dString ) )
				( Status  sProperty  sPackage )
			)
			( Objects
				( ValidObjects  oGate  oGateDefn  oBlock  oPart  oDesign  oSystem  oPartDefn )
				( NoInherit
					( oGate oPin )
				)
			)
			( Analysis
			)
		)
		( Attribute
			( Name "SEC_TYPE" )
			( Description " " )
			( Value
				( DataType ( dString ) )
				( Status  sProperty  sPackage )
			)
			( Objects
				( ValidObjects  oGate  oGateDefn  oBlock  oPart  oDesign  oSystem  oPartDefn )
				( NoInherit
					( oGate oPin )
				)
			)
			( Analysis
			)
		)
		( Attribute
			( Name "$sec" )
			( Description "" )
			( Value
				( DataType ( dString ) )
				( Status  sProperty )
			)
			( Objects
				( ValidObjects  oAll )
			)
			( Analysis
			)
		)
		( Attribute
			( Name "$location" )
			( Description "" )
			( Value
				( DataType ( dString ) )
				( Status  sProperty )
			)
			( Objects
				( ValidObjects  oAll )
			)
			( Analysis
			)
		)
		( Attribute
			( Name "WACKO" )
			( Description " " )
			( Value
				( DataType ( dString ) )
				( Status  sProperty  sPackage )
			)
			( Objects
				( ValidObjects  oGate  oGateDefn  oBlock  oPart  oDesign  oSystem  oPartDefn )
				( NoInherit
					( oGate oPin )
				)
			)
			( Analysis
			)
		)
		( Attribute
			( Name "BODY_TYPE" )
			( Description " " )
			( Value
				( DataType ( dString ) )
				( Status  sProperty  sPackage )
			)
			( Objects
				( ValidObjects  oGate  oBlock  oPart  oDesign  oSystem  oGateDefn  oPartDefn )
			)
			( Analysis
			)
		)
	)
	( designConstraints
		( ruleChanges
			( allRules )
			( design "p12v_stby"
			)
			( signal "@mstr_symbols.p12v_stby(sch_1):g"
				( objectFlag fObjectAlias )
				( objectStatus "g" )
			)
			( signal "@mstr_symbols.p12v_stby(sch_1):page1_g"
				( objectFlag fObjectAlias )
				( objectStatus "page1_g" )
			)
			( signal "@mstr_symbols.p12v_stby(sch_1):p12v_stby"
				( alias ( signalRef "@mstr_symbols.p12v_stby(sch_1):page1_p12v_stby") )
				( alias ( signalRef "@mstr_symbols.p12v_stby(sch_1):page1_g") )
				( alias ( signalRef "@mstr_symbols.p12v_stby(sch_1):g") )
				( objectStatus "p12v_stby" )
			)
			( signal "@mstr_symbols.p12v_stby(sch_1):page1_p12v_stby"
				( objectFlag fObjectAlias )
				( objectStatus "page1_p12v_stby" )
			)
		)
	)
)
